(kicad_pcb
	(version 20241229)
	(generator "pcbnew")
	(generator_version "9.0")
	(general
		(thickness 1.62)
		(legacy_teardrops no)
	)
	(paper "A4")
	(title_block
		(title "OCuLink to 10GbE adapter")
		(date "2026-02-23")
		(rev "1.1.0")
		(company "Antmicro Ltd")
		(comment 1 "www.antmicro.com")
		(comment 9 "footprints 276-280 of 510")
	)
	(layers
		(0 "F.Cu" signal)
		(4 "In1.Cu" signal)
		(6 "In2.Cu" signal)
		(8 "In3.Cu" signal)
		(10 "In4.Cu" signal)
		(12 "In5.Cu" signal)
		(14 "In6.Cu" signal)
		(2 "B.Cu" signal)
		(9 "F.Adhes" user "F.Adhesive")
		(11 "B.Adhes" user "B.Adhesive")
		(13 "F.Paste" user)
		(15 "B.Paste" user)
		(5 "F.SilkS" user "F.Silkscreen")
		(7 "B.SilkS" user "B.Silkscreen")
		(1 "F.Mask" user)
		(3 "B.Mask" user)
		(17 "Dwgs.User" user "User.Drawings")
		(19 "Cmts.User" user "User.Comments")
		(21 "Eco1.User" user "User.Eco1")
		(23 "Eco2.User" user "User.Eco2")
		(25 "Edge.Cuts" user)
		(27 "Margin" user)
		(31 "F.CrtYd" user "F.Courtyard")
		(29 "B.CrtYd" user "B.Courtyard")
		(35 "F.Fab" user)
		(33 "B.Fab" user)
	)
	(footprint "antmicro-footprints:LED_0603_1608Metric_G"
		(layer "F.Cu")
		(at 76.7 52.65 -90)
		(descr "LED SMD 0603 Green")
		(tags "LED SMD 0603 Green")
		(property "Reference" "D3"
			(at -0.607 1.31 90)
			(layer "F.SilkS")
			(effects
				(font
					(size 0.7 0.7)
					(thickness 0.15)
				)
				(justify right top)
			)
		)
		(property "Value" "LED_G_0603_LG_L29K-G2J1-24-Z"
			(at -0.001 1.599 90)
			(layer "F.Fab")
			(hide yes)
			(effects
				(font
					(size 0.7 0.7)
					(thickness 0.15)
				)
				(justify right top)
			)
		)
		(property "Datasheet" "https://look.ams-osram.com/m/19ee86b3ae0ee95b/original/LG-L29K.pdf"
			(at 0 0 90)
			(layer "F.Fab")
			(hide yes)
			(effects
				(font
					(size 1.27 1.27)
					(thickness 0.15)
				)
			)
		)
		(property "Description" "LED, Green, SMD, 0603, 20 mA, 1.7 V, 570 nm"
			(at 0 0 90)
			(layer "F.Fab")
			(hide yes)
			(effects
				(font
					(size 1.27 1.27)
					(thickness 0.15)
				)
			)
		)
		(property "MPN" "LG L29K-G2J1-24-Z"
			(at 0 0 270)
			(unlocked yes)
			(layer "F.Fab")
			(hide yes)
			(effects
				(font
					(size 1 1)
					(thickness 0.15)
				)
			)
		)
		(property "Manufacturer" "OSRAM"
			(at 0 0 270)
			(unlocked yes)
			(layer "F.Fab")
			(hide yes)
			(effects
				(font
					(size 1 1)
					(thickness 0.15)
				)
			)
		)
		(property "Color" "Green"
			(at 0 0 270)
			(unlocked yes)
			(layer "F.Fab")
			(hide yes)
			(effects
				(font
					(size 1 1)
					(thickness 0.15)
				)
			)
		)
		(property "Author" "Antmicro"
			(at 0 0 270)
			(unlocked yes)
			(layer "F.Fab")
			(hide yes)
			(effects
				(font
					(size 1 1)
					(thickness 0.15)
				)
			)
		)
		(property "License" "Apache-2.0"
			(at 0 0 270)
			(unlocked yes)
			(layer "F.Fab")
			(hide yes)
			(effects
				(font
					(size 1 1)
					(thickness 0.15)
				)
			)
		)
		(sheetname "/Power/")
		(sheetfile "power.kicad_sch")
		(attr smd)
		(fp_line
			(start 0.22 0.35)
			(end -0.22 0.35)
			(stroke
				(width 0.15)
				(type solid)
			)
			(layer "F.SilkS")
		)
		(fp_line
			(start -0.094672 0.201008)
			(end -0.094672 -0.198992)
			(stroke
				(width 0.1)
				(type solid)
			)
			(layer "F.SilkS")
		)
		(fp_line
			(start 0.105328 0.201008)
			(end -0.094672 0.001008)
			(stroke
				(width 0.1)
				(type solid)
			)
			(layer "F.SilkS")
		)
		(fp_line
			(start 0.105328 0.201008)
			(end 0.105328 -0.198992)
			(stroke
				(width 0.1)
				(type solid)
			)
			(layer "F.SilkS")
		)
		(fp_line
			(start -0.094672 0.001008)
			(end -0.24 0.001008)
			(stroke
				(width 0.1)
				(type solid)
			)
			(layer "F.SilkS")
		)
		(fp_line
			(start -0.094672 0.001008)
			(end 0.105328 -0.198992)
			(stroke
				(width 0.1)
				(type solid)
			)
			(layer "F.SilkS")
		)
		(fp_line
			(start 0.105328 0.001008)
			(end 0.24 0.001)
			(stroke
				(width 0.1)
				(type solid)
			)
			(layer "F.SilkS")
		)
		(fp_line
			(start -1.18 -0.319)
			(end -1.18 0.321)
			(stroke
				(width 0.15)
				(type solid)
			)
			(layer "F.SilkS")
		)
		(fp_line
			(start 0.22 -0.35)
			(end -0.22 -0.35)
			(stroke
				(width 0.15)
				(type solid)
			)
			(layer "F.SilkS")
		)
		(fp_rect
			(start 1.25 0.65)
			(end -1.25 -0.65)
			(stroke
				(width 0.05)
				(type solid)
			)
			(fill no)
			(layer "F.CrtYd")
		)
		(fp_line
			(start -0.199 0.2)
			(end -0.199 0.1)
			(stroke
				(width 0.15)
				(type solid)
			)
			(layer "F.Fab")
		)
		(fp_line
			(start 0.201 0.2)
			(end 0.201 0)
			(stroke
				(width 0.15)
				(type solid)
			)
			(layer "F.Fab")
		)
		(fp_line
			(start -0.199 0)
			(end -0.597 0)
			(stroke
				(width 0.15)
				(type solid)
			)
			(layer "F.Fab")
		)
		(fp_line
			(start -0.101 0)
			(end 0.201 0.2)
			(stroke
				(width 0.15)
				(type solid)
			)
			(layer "F.Fab")
		)
		(fp_line
			(start 0.201 0)
			(end 0.201 -0.202)
			(stroke
				(width 0.15)
				(type solid)
			)
			(layer "F.Fab")
		)
		(fp_line
			(start 0.599 0)
			(end 0.201 0)
			(stroke
				(width 0.15)
				(type solid)
			)
			(layer "F.Fab")
		)
		(fp_line
			(start -0.199 -0.202)
			(end -0.199 0.1)
			(stroke
				(width 0.15)
				(type solid)
			)
			(layer "F.Fab")
		)
		(fp_line
			(start 0.201 -0.202)
			(end -0.101 0)
			(stroke
				(width 0.15)
				(type solid)
			)
			(layer "F.Fab")
		)
		(fp_rect
			(start 0.848 0.4)
			(end -0.85 -0.402)
			(stroke
				(width 0.15)
				(type solid)
			)
			(fill no)
			(layer "F.Fab")
		)
		(fp_text user "Author: Antmicro"
			(at -1.4224 4.799 270)
			(layer "F.Fab")
			(effects
				(font
					(size 0.7 0.7)
					(thickness 0.15)
				)
				(justify left bottom)
			)
		)
		(fp_text user "${REFERENCE}"
			(at -1.4224 5.999 270)
			(layer "F.Fab")
			(effects
				(font
					(size 0.7 0.7)
					(thickness 0.15)
				)
				(justify left bottom)
			)
		)
		(fp_text user "License: Apache-2.0"
			(at -1.4224 3.599 270)
			(layer "F.Fab")
			(effects
				(font
					(size 0.7 0.7)
					(thickness 0.15)
				)
				(justify left bottom)
			)
		)
		(pad "1" smd roundrect
			(at -0.7 0 90)
			(size 0.8 1)
			(layers "F.Cu" "F.Mask" "F.Paste")
			(roundrect_rratio 0.2)
			(net 28 "GND")
			(pinfunction "C")
			(pintype "passive")
		)
		(pad "2" smd roundrect
			(at 0.7 0 90)
			(size 0.8 1)
			(layers "F.Cu" "F.Mask" "F.Paste")
			(roundrect_rratio 0.2)
			(net 75 "Net-(D3-A)")
			(pinfunction "A")
			(pintype "passive")
		)
	)
	(footprint "antmicro-footprints:C_0805_2012Metric"
		(layer "F.Cu")
		(at 71.3 110.39 90)
		(descr "Capacitor SMD 0805")
		(tags "capacitor SMD 0805")
		(property "Reference" "C164"
			(at -3.63 4.33 90)
			(layer "F.SilkS")
			(effects
				(font
					(size 0.7 0.7)
					(thickness 0.15)
				)
				(justify left bottom)
			)
		)
		(property "Value" "C_100u_0805"
			(at -2.055717 1.963153 90)
			(layer "F.Fab")
			(hide yes)
			(effects
				(font
					(size 0.7 0.7)
					(thickness 0.15)
				)
				(justify left bottom)
			)
		)
		(property "Datasheet" "https://www.murata.com/products/productdetail?partno=GRM21BR60J107ME15%23"
			(at 0 0 90)
			(layer "F.Fab")
			(hide yes)
			(effects
				(font
					(size 1.27 1.27)
					(thickness 0.15)
				)
			)
		)
		(property "Description" "SMD Multilayer Ceramic Capacitor, 100 µF, 6.3 V, 0805 [2012 Metric], ± 20%, X5R, GRM Series"
			(at 0 0 90)
			(layer "F.Fab")
			(hide yes)
			(effects
				(font
					(size 1.27 1.27)
					(thickness 0.15)
				)
			)
		)
		(property "MPN" "GRM21BR60J107ME15L"
			(at 0 0 90)
			(unlocked yes)
			(layer "F.Fab")
			(hide yes)
			(effects
				(font
					(size 1 1)
					(thickness 0.15)
				)
			)
		)
		(property "Manufacturer" "Murata"
			(at 0 0 90)
			(unlocked yes)
			(layer "F.Fab")
			(hide yes)
			(effects
				(font
					(size 1 1)
					(thickness 0.15)
				)
			)
		)
		(property "License" "Apache-2.0"
			(at 0 0 90)
			(unlocked yes)
			(layer "F.Fab")
			(hide yes)
			(effects
				(font
					(size 1 1)
					(thickness 0.15)
				)
			)
		)
		(property "Author" "Antmicro"
			(at 0 0 90)
			(unlocked yes)
			(layer "F.Fab")
			(hide yes)
			(effects
				(font
					(size 1 1)
					(thickness 0.15)
				)
			)
		)
		(property "Val" "100u"
			(at 0 0 90)
			(unlocked yes)
			(layer "F.Fab")
			(hide yes)
			(effects
				(font
					(size 1 1)
					(thickness 0.15)
				)
			)
		)
		(property "Voltage" ""
			(at 0 0 90)
			(unlocked yes)
			(layer "F.Fab")
			(hide yes)
			(effects
				(font
					(size 1 1)
					(thickness 0.15)
				)
			)
		)
		(property "Dielectric" ""
			(at 0 0 90)
			(unlocked yes)
			(layer "F.Fab")
			(hide yes)
			(effects
				(font
					(size 1 1)
					(thickness 0.15)
				)
			)
		)
		(property "Public" "False"
			(at 0 0 90)
			(unlocked yes)
			(layer "F.Fab")
			(hide yes)
			(effects
				(font
					(size 1 1)
					(thickness 0.15)
				)
			)
		)
		(sheetname "/X710-AT2 power/")
		(sheetfile "x710-at2-power.kicad_sch")
		(attr smd)
		(fp_line
			(start -0.3 -0.7)
			(end 0.3 -0.7)
			(stroke
				(width 0.15)
				(type solid)
			)
			(layer "F.SilkS")
		)
		(fp_line
			(start -0.3 0.7)
			(end 0.3 0.7)
			(stroke
				(width 0.15)
				(type solid)
			)
			(layer "F.SilkS")
		)
		(fp_rect
			(start 1.95 -0.9)
			(end -1.95 0.9)
			(stroke
				(width 0.05)
				(type default)
			)
			(fill no)
			(layer "F.CrtYd")
		)
		(fp_rect
			(start -0.95 -0.675)
			(end 0.95 0.675)
			(stroke
				(width 0.15)
				(type solid)
			)
			(fill no)
			(layer "F.Fab")
		)
		(pad "1" smd roundrect
			(at -1.1 0 90)
			(size 1.2 1.3)
			(layers "F.Cu" "F.Mask" "F.Paste")
			(roundrect_rratio 0.25)
			(net 28 "GND")
			(pintype "passive")
		)
		(pad "2" smd roundrect
			(at 1.1 0 90)
			(size 1.2 1.3)
			(layers "F.Cu" "F.Mask" "F.Paste")
			(roundrect_rratio 0.25)
			(net 5 "P0_AVDDL")
			(pintype "passive")
		)
	)
	(footprint "antmicro-footprints:C_0402_1005Metric"
		(layer "F.Cu")
		(at 56.399998 90.1)
		(descr "Capacitor SMD 0402")
		(tags "capacitor SMD 0402")
		(property "Reference" "C10"
			(at -2.809998 0.94 0)
			(layer "F.SilkS")
			(effects
				(font
					(size 0.7 0.7)
					(thickness 0.15)
				)
				(justify left bottom)
			)
		)
		(property "Value" "C_100n_0402"
			(at -1.022927 2.155213 0)
			(layer "F.Fab")
			(hide yes)
			(effects
				(font
					(size 0.7 0.7)
					(thickness 0.15)
				)
				(justify left bottom)
			)
		)
		(property "Datasheet" "https://www.murata.com/products/productdetail?partno=GRM155R61H104KE14%23"
			(at 0 0 0)
			(layer "F.Fab")
			(hide yes)
			(effects
				(font
					(size 1.27 1.27)
					(thickness 0.15)
				)
			)
		)
		(property "Description" "SMD Multilayer Ceramic Capacitor, 0.1 µF, 50 V, 0402 [1005 Metric], ± 10%, X5R, GRM Series"
			(at 0 0 0)
			(layer "F.Fab")
			(hide yes)
			(effects
				(font
					(size 1.27 1.27)
					(thickness 0.15)
				)
			)
		)
		(property "MPN" "GRM155R61H104KE14D"
			(at 0 0 0)
			(unlocked yes)
			(layer "F.Fab")
			(hide yes)
			(effects
				(font
					(size 1 1)
					(thickness 0.15)
				)
			)
		)
		(property "Manufacturer" "Murata"
			(at 0 0 0)
			(unlocked yes)
			(layer "F.Fab")
			(hide yes)
			(effects
				(font
					(size 1 1)
					(thickness 0.15)
				)
			)
		)
		(property "License" "Apache-2.0"
			(at 0 0 0)
			(unlocked yes)
			(layer "F.Fab")
			(hide yes)
			(effects
				(font
					(size 1 1)
					(thickness 0.15)
				)
			)
		)
		(property "Author" "Antmicro"
			(at 0 0 0)
			(unlocked yes)
			(layer "F.Fab")
			(hide yes)
			(effects
				(font
					(size 1 1)
					(thickness 0.15)
				)
			)
		)
		(property "Val" "100n"
			(at 0 0 0)
			(unlocked yes)
			(layer "F.Fab")
			(hide yes)
			(effects
				(font
					(size 1 1)
					(thickness 0.15)
				)
			)
		)
		(property "Voltage" "50V"
			(at 0 0 0)
			(unlocked yes)
			(layer "F.Fab")
			(hide yes)
			(effects
				(font
					(size 1 1)
					(thickness 0.15)
				)
			)
		)
		(property "Dielectric" "X5R"
			(at 0 0 0)
			(unlocked yes)
			(layer "F.Fab")
			(hide yes)
			(effects
				(font
					(size 1 1)
					(thickness 0.15)
				)
			)
		)
		(sheetname "/Power/")
		(sheetfile "power.kicad_sch")
		(attr smd)
		(fp_rect
			(start -0.925 -0.47)
			(end 0.925 0.47)
			(stroke
				(width 0.05)
				(type default)
			)
			(fill no)
			(layer "F.CrtYd")
		)
		(fp_line
			(start -0.494 -0.25)
			(end 0.504 -0.25)
			(stroke
				(width 0.15)
				(type solid)
			)
			(layer "F.Fab")
		)
		(fp_line
			(start -0.494 0.248)
			(end -0.494 -0.25)
			(stroke
				(width 0.15)
				(type solid)
			)
			(layer "F.Fab")
		)
		(fp_line
			(start 0.504 -0.25)
			(end 0.504 0.248)
			(stroke
				(width 0.15)
				(type solid)
			)
			(layer "F.Fab")
		)
		(fp_line
			(start 0.504 0.248)
			(end -0.494 0.248)
			(stroke
				(width 0.15)
				(type solid)
			)
			(layer "F.Fab")
		)
		(pad "1" smd roundrect
			(at -0.48 0)
			(size 0.59 0.64)
			(layers "F.Cu" "F.Mask" "F.Paste")
			(roundrect_rratio 0.25)
			(net 318 "/Power/VCCD_BST")
			(pintype "passive")
		)
		(pad "2" smd roundrect
			(at 0.48 0)
			(size 0.59 0.64)
			(layers "F.Cu" "F.Mask" "F.Paste")
			(roundrect_rratio 0.25)
			(net 334 "/Power/VCCD_SW")
			(pintype "passive")
		)
	)
	(footprint "antmicro-footprints:C_0603_1608Metric_EIA"
		(layer "F.Cu")
		(at 77.2 85 180)
		(descr "Capacitor SMD 0603, IPC-7351 Density Level A")
		(tags "Capacitor 0603")
		(property "Reference" "C152"
			(at -1.4 7.958 0)
			(layer "F.SilkS")
			(effects
				(font
					(size 0.7 0.7)
					(thickness 0.15)
				)
				(justify right top)
			)
		)
		(property "Value" "C_22u_16V_0603"
			(at -1.42757 1.770288 0)
			(layer "F.Fab")
			(hide yes)
			(effects
				(font
					(size 0.7 0.7)
					(thickness 0.15)
				)
				(justify right top)
			)
		)
		(property "Datasheet" "https://product.samsungsem.com/mlcc/CL10A226MO7JZN.do"
			(at 0 0 0)
			(layer "F.Fab")
			(hide yes)
			(effects
				(font
					(size 1.27 1.27)
					(thickness 0.15)
				)
			)
		)
		(property "Description" "SMD Multilayer Ceramic Capacitor"
			(at 0 0 0)
			(layer "F.Fab")
			(hide yes)
			(effects
				(font
					(size 1.27 1.27)
					(thickness 0.15)
				)
			)
		)
		(property "MPN" "CL10A226MO7JZNC"
			(at 0 0 180)
			(unlocked yes)
			(layer "F.Fab")
			(hide yes)
			(effects
				(font
					(size 1 1)
					(thickness 0.15)
				)
			)
		)
		(property "Manufacturer" "Samsung Electro-Mechanics"
			(at 0 0 180)
			(unlocked yes)
			(layer "F.Fab")
			(hide yes)
			(effects
				(font
					(size 1 1)
					(thickness 0.15)
				)
			)
		)
		(property "License" "Apache-2.0"
			(at 0 0 180)
			(unlocked yes)
			(layer "F.Fab")
			(hide yes)
			(effects
				(font
					(size 1 1)
					(thickness 0.15)
				)
			)
		)
		(property "Author" "Antmicro"
			(at 0 0 180)
			(unlocked yes)
			(layer "F.Fab")
			(hide yes)
			(effects
				(font
					(size 1 1)
					(thickness 0.15)
				)
			)
		)
		(property "Val" "22u"
			(at 0 0 180)
			(unlocked yes)
			(layer "F.Fab")
			(hide yes)
			(effects
				(font
					(size 1 1)
					(thickness 0.15)
				)
			)
		)
		(property "Voltage" "16V"
			(at 0 0 180)
			(unlocked yes)
			(layer "F.Fab")
			(hide yes)
			(effects
				(font
					(size 1 1)
					(thickness 0.15)
				)
			)
		)
		(property "Dielectric" ""
			(at 0 0 180)
			(unlocked yes)
			(layer "F.Fab")
			(hide yes)
			(effects
				(font
					(size 1 1)
					(thickness 0.15)
				)
			)
		)
		(sheetname "/X710-AT2 power/")
		(sheetfile "x710-at2-power.kicad_sch")
		(attr smd)
		(fp_line
			(start -0.15 0.55)
			(end 0.15 0.55)
			(stroke
				(width 0.15)
				(type solid)
			)
			(layer "F.SilkS")
		)
		(fp_line
			(start -0.15 -0.55)
			(end 0.15 -0.55)
			(stroke
				(width 0.15)
				(type solid)
			)
			(layer "F.SilkS")
		)
		(fp_rect
			(start -1.25 -0.65)
			(end 1.25 0.65)
			(stroke
				(width 0.05)
				(type solid)
			)
			(fill no)
			(layer "F.CrtYd")
		)
		(fp_rect
			(start -0.8 -0.45)
			(end 0.8 0.45)
			(stroke
				(width 0.15)
				(type solid)
			)
			(fill no)
			(layer "F.Fab")
		)
		(pad "1" smd roundrect
			(at -0.7 0 180)
			(size 0.8 1.1)
			(layers "F.Cu" "F.Mask" "F.Paste")
			(roundrect_rratio 0.2)
			(net 28 "GND")
			(pintype "passive")
		)
		(pad "2" smd roundrect
			(at 0.7 0 180)
			(size 0.8 1.1)
			(layers "F.Cu" "F.Mask" "F.Paste")
			(roundrect_rratio 0.2)
			(net 7 "+3V3")
			(pintype "passive")
		)
	)
	(footprint "antmicro-footprints:FB_0603_1608Metric"
		(layer "F.Cu")
		(at 67.25 113.1)
		(property "Reference" "FB6"
			(at -3.2 0.46 0)
			(layer "F.SilkS")
			(effects
				(font
					(size 0.7 0.7)
					(thickness 0.15)
				)
				(justify left bottom)
			)
		)
		(property "Value" "FB_33Z_3A_Murata-BLM18PG_0603"
			(at 0 1.5 0)
			(layer "F.Fab")
			(hide yes)
			(effects
				(font
					(size 0.7 0.7)
					(thickness 0.15)
				)
				(justify left bottom)
			)
		)
		(property "Datasheet" "https://www.murata.com/products/productdata/8796737273886/QNFA9101.pdf?1649080818000"
			(at 0 0 0)
			(layer "F.Fab")
			(hide yes)
			(effects
				(font
					(size 1.27 1.27)
					(thickness 0.15)
				)
			)
		)
		(property "Description" "Ferrite Bead, 0603 [1608 Metric], 33 ohm, 3 A, BLM18PG, 0.025 ohm, ± 25%, DC power line"
			(at 0 0 0)
			(layer "F.Fab")
			(hide yes)
			(effects
				(font
					(size 1.27 1.27)
					(thickness 0.15)
				)
			)
		)
		(property "Val" "33Z/3A"
			(at 0 0 0)
			(unlocked yes)
			(layer "F.Fab")
			(hide yes)
			(effects
				(font
					(size 1 1)
					(thickness 0.15)
				)
			)
		)
		(property "MPN" "BLM18PG330SH1D"
			(at 0 0 0)
			(unlocked yes)
			(layer "F.Fab")
			(hide yes)
			(effects
				(font
					(size 1 1)
					(thickness 0.15)
				)
			)
		)
		(property "Manufacturer" "Murata"
			(at 0 0 0)
			(unlocked yes)
			(layer "F.Fab")
			(hide yes)
			(effects
				(font
					(size 1 1)
					(thickness 0.15)
				)
			)
		)
		(property "Current" ""
			(at 0 0 0)
			(unlocked yes)
			(layer "F.Fab")
			(hide yes)
			(effects
				(font
					(size 1 1)
					(thickness 0.15)
				)
			)
		)
		(property "Author" "Antmicro"
			(at 0 0 0)
			(unlocked yes)
			(layer "F.Fab")
			(hide yes)
			(effects
				(font
					(size 1 1)
					(thickness 0.15)
				)
			)
		)
		(property "License" "Apache-2.0"
			(at 0 0 0)
			(unlocked yes)
			(layer "F.Fab")
			(hide yes)
			(effects
				(font
					(size 1 1)
					(thickness 0.15)
				)
			)
		)
		(sheetname "/X710-AT2 power/")
		(sheetfile "x710-at2-power.kicad_sch")
		(attr smd)
		(fp_line
			(start -0.15 -0.4)
			(end 0.15 -0.4)
			(stroke
				(width 0.15)
				(type solid)
			)
			(layer "F.SilkS")
		)
		(fp_line
			(start -0.15 0.4)
			(end 0.15 0.4)
			(stroke
				(width 0.15)
				(type solid)
			)
			(layer "F.SilkS")
		)
		(fp_rect
			(start -1.25 -0.65)
			(end 1.25 0.65)
			(stroke
				(width 0.05)
				(type solid)
			)
			(fill no)
			(layer "F.CrtYd")
		)
		(fp_line
			(start -0.803 0.406)
			(end -0.803 -0.408)
			(stroke
				(width 0.15)
				(type solid)
			)
			(layer "F.Fab")
		)
		(fp_line
			(start 0.8 -0.408)
			(end -0.803 -0.408)
			(stroke
				(width 0.15)
				(type solid)
			)
			(layer "F.Fab")
		)
		(fp_line
			(start 0.8 -0.408)
			(end 0.8 0.406)
			(stroke
				(width 0.15)
				(type solid)
			)
			(layer "F.Fab")
		)
		(fp_line
			(start 0.8 0.406)
			(end -0.803 0.406)
			(stroke
				(width 0.15)
				(type solid)
			)
			(layer "F.Fab")
		)
		(pad "1" smd roundrect
			(at -0.7 0)
			(size 0.8 1)
			(layers "F.Cu" "F.Mask" "F.Paste")
			(roundrect_rratio 0.2)
			(net 302 "+1V0")
			(pintype "passive")
		)
		(pad "2" smd roundrect
			(at 0.7 0)
			(size 0.8 1)
			(layers "F.Cu" "F.Mask" "F.Paste")
			(roundrect_rratio 0.2)
			(net 14 "P1_AVDDL")
			(pintype "passive")
		)
	)
)
